# S9S_MB_2U (Grand Teton) — schematic netlist excerpt (pin names and nets, part order shuffled) for the footprints in the layout excerpt that follows; sources: Cadence DE-HDL packaged netlist, KiCad conversion of 03242023_DA0F0TMBIJ0_F0T_Motherboard_J_brd_V01_OCP.brd

R3874  Q_RES  0 5% CHIP  pkg 0402LF  page 163 : A = P12V_OCP_IMON_2 ; B = P12V_OCP_V3_2_ISENSE_MPS_TIC
PR150  Q_RES  8.87K 1% EMPTY  pkg 0402LF  page 267 : A = PVCCIN_CPU0_LSET2 ; B = GND

(kicad_pcb
	(version 20260206)
	(generator "pcbnew")
	(generator_version "10.0")
	(general
		(thickness 1.6)
		(legacy_teardrops no)
	)
	(paper "A4")
	(title_block
		(title "03242023_DA0F0TMBIJ0_F0T_Motherboard_J_brd_V01_OCP.brd")
		(comment 1 "Grand Teton / footprints 3495-3496 of 6105")
	)
	(layers
		(0 "F.Cu" signal "TOP")
		(4 "In1.Cu" signal "GND")
		(6 "In2.Cu" signal "IN1")
		(8 "In3.Cu" signal "GND1")
		(10 "In4.Cu" signal "IN2")
		(12 "In5.Cu" signal "GND2")
		(14 "In6.Cu" signal "IN3")
		(16 "In7.Cu" signal "GND3")
		(18 "In8.Cu" signal "VCC")
		(20 "In9.Cu" signal "VCC1")
		(22 "In10.Cu" signal "GND4")
		(24 "In11.Cu" signal "IN4")
		(26 "In12.Cu" signal "GND5")
		(28 "In13.Cu" signal "IN5")
		(30 "In14.Cu" signal "GND6")
		(32 "In15.Cu" signal "IN6")
		(34 "In16.Cu" signal "GND7")
		(2 "B.Cu" signal "BOTTOM")
		(9 "F.Adhes" user "F.Adhesive")
		(11 "B.Adhes" user "B.Adhesive")
		(13 "F.Paste" user "Package Geometry/Pastemask Top")
		(15 "B.Paste" user "Package Geometry/Pastemask Bottom")
		(5 "F.SilkS" user "Ref Des/Silkscreen Top")
		(7 "B.SilkS" user "Ref Des/Silkscreen Bottom")
		(1 "F.Mask" user "Board Geometry/Soldermask Top")
		(3 "B.Mask" user "Board Geometry/Soldermask Bottom")
		(17 "Dwgs.User" user "User.Drawings")
		(19 "Cmts.User" user "User.Comments")
		(21 "Eco1.User" user "User.Eco1")
		(23 "Eco2.User" user "User.Eco2")
		(25 "Edge.Cuts" user "Board Geometry/Outline")
		(27 "Margin" user)
		(31 "F.CrtYd" user "Package Geometry/Place Bound Top")
		(29 "B.CrtYd" user "Package Geometry/Place Bound Bottom")
		(35 "F.Fab" user "Ref Des/Assembly Top")
		(33 "B.Fab" user "Ref Des/Assembly Bottom")
	)
	(footprint ""
		(layer "F.Cu")
		(at 352.217736 -338.86013)
		(property "Reference" "PR150"
			(at 0 0 0)
			(layer "F.SilkS")
			(hide yes)
			(effects
				(font
					(size 1.27 1.27)
				)
			)
		)
		(property "Value" ""
			(at 0 0 0)
			(layer "F.Fab")
			(effects
				(font
					(size 1.27 1.27)
				)
			)
		)
		(duplicate_pad_numbers_are_jumpers no)
		(fp_line
			(start -0.7874 -0.4064)
			(end 0.7874 -0.4064)
			(stroke
				(width 0.1524)
				(type default)
			)
			(layer "F.SilkS")
		)
		(fp_line
			(start -0.7874 0.4064)
			(end -0.7874 -0.4064)
			(stroke
				(width 0.1524)
				(type default)
			)
			(layer "F.SilkS")
		)
		(fp_line
			(start 0.7874 -0.4064)
			(end 0.7874 0.4064)
			(stroke
				(width 0.1524)
				(type default)
			)
			(layer "F.SilkS")
		)
		(fp_line
			(start 0.7874 0.4064)
			(end -0.7874 0.4064)
			(stroke
				(width 0.1524)
				(type default)
			)
			(layer "F.SilkS")
		)
		(fp_line
			(start -0.67945 -0.305054)
			(end -0.12065 -0.305054)
			(stroke
				(width 0.1)
				(type default)
			)
			(layer "F.Fab")
		)
		(fp_line
			(start -0.67945 0.3048)
			(end -0.67945 -0.305054)
			(stroke
				(width 0.1)
				(type default)
			)
			(layer "F.Fab")
		)
		(fp_line
			(start -0.12065 -0.305054)
			(end -0.12065 -0.2794)
			(stroke
				(width 0.1)
				(type default)
			)
			(layer "F.Fab")
		)
		(fp_line
			(start -0.12065 -0.2794)
			(end 0.12065 -0.2794)
			(stroke
				(width 0.1)
				(type default)
			)
			(layer "F.Fab")
		)
		(fp_line
			(start -0.12065 0.2794)
			(end -0.12065 0.3048)
			(stroke
				(width 0.1)
				(type default)
			)
			(layer "F.Fab")
		)
		(fp_line
			(start -0.12065 0.3048)
			(end -0.67945 0.3048)
			(stroke
				(width 0.1)
				(type default)
			)
			(layer "F.Fab")
		)
		(fp_line
			(start 0.120396 0.2794)
			(end -0.12065 0.2794)
			(stroke
				(width 0.1)
				(type default)
			)
			(layer "F.Fab")
		)
		(fp_line
			(start 0.120396 0.3048)
			(end 0.120396 0.2794)
			(stroke
				(width 0.1)
				(type default)
			)
			(layer "F.Fab")
		)
		(fp_line
			(start 0.12065 -0.3048)
			(end 0.67945 -0.3048)
			(stroke
				(width 0.1)
				(type default)
			)
			(layer "F.Fab")
		)
		(fp_line
			(start 0.12065 -0.2794)
			(end 0.12065 -0.3048)
			(stroke
				(width 0.1)
				(type default)
			)
			(layer "F.Fab")
		)
		(fp_line
			(start 0.67945 -0.3048)
			(end 0.67945 0.3048)
			(stroke
				(width 0.1)
				(type default)
			)
			(layer "F.Fab")
		)
		(fp_line
			(start 0.67945 0.3048)
			(end 0.120396 0.3048)
			(stroke
				(width 0.1)
				(type default)
			)
			(layer "F.Fab")
		)
		(pad "1" smd circle
			(at -0.40005 0)
			(size 0 0)
			(layers "F.Cu" "F.Mask" "F.Paste")
			(net "PVCCIN_CPU0_LSET2")
		)
		(pad "2" smd circle
			(at 0.40005 0)
			(size 0 0)
			(layers "F.Cu" "F.Mask" "F.Paste")
			(net "GND")
		)
	)
	(footprint ""
		(layer "F.Cu")
		(at 61.543438 -31.887922 90)
		(property "Reference" "R3874"
			(at 0 0 90)
			(layer "F.SilkS")
			(hide yes)
			(effects
				(font
					(size 1.27 1.27)
				)
			)
		)
		(property "Value" ""
			(at 0 0 90)
			(layer "F.Fab")
			(effects
				(font
					(size 1.27 1.27)
				)
			)
		)
		(duplicate_pad_numbers_are_jumpers no)
		(fp_line
			(start 0.7874 -0.4064)
			(end 0.7874 0.4064)
			(stroke
				(width 0.1524)
				(type default)
			)
			(layer "F.SilkS")
		)
		(fp_line
			(start -0.7874 -0.4064)
			(end 0.7874 -0.4064)
			(stroke
				(width 0.1524)
				(type default)
			)
			(layer "F.SilkS")
		)
		(fp_line
			(start 0.7874 0.4064)
			(end -0.7874 0.4064)
			(stroke
				(width 0.1524)
				(type default)
			)
			(layer "F.SilkS")
		)
		(fp_line
			(start -0.7874 0.4064)
			(end -0.7874 -0.4064)
			(stroke
				(width 0.1524)
				(type default)
			)
			(layer "F.SilkS")
		)
		(fp_line
			(start -0.12065 -0.305054)
			(end -0.12065 -0.2794)
			(stroke
				(width 0.1)
				(type default)
			)
			(layer "F.Fab")
		)
		(fp_line
			(start -0.67945 -0.305054)
			(end -0.12065 -0.305054)
			(stroke
				(width 0.1)
				(type default)
			)
			(layer "F.Fab")
		)
		(fp_line
			(start 0.67945 -0.3048)
			(end 0.67945 0.3048)
			(stroke
				(width 0.1)
				(type default)
			)
			(layer "F.Fab")
		)
		(fp_line
			(start 0.12065 -0.3048)
			(end 0.67945 -0.3048)
			(stroke
				(width 0.1)
				(type default)
			)
			(layer "F.Fab")
		)
		(fp_line
			(start 0.12065 -0.2794)
			(end 0.12065 -0.3048)
			(stroke
				(width 0.1)
				(type default)
			)
			(layer "F.Fab")
		)
		(fp_line
			(start -0.12065 -0.2794)
			(end 0.12065 -0.2794)
			(stroke
				(width 0.1)
				(type default)
			)
			(layer "F.Fab")
		)
		(fp_line
			(start 0.120396 0.2794)
			(end -0.12065 0.2794)
			(stroke
				(width 0.1)
				(type default)
			)
			(layer "F.Fab")
		)
		(fp_line
			(start -0.12065 0.2794)
			(end -0.12065 0.3048)
			(stroke
				(width 0.1)
				(type default)
			)
			(layer "F.Fab")
		)
		(fp_line
			(start 0.67945 0.3048)
			(end 0.120396 0.3048)
			(stroke
				(width 0.1)
				(type default)
			)
			(layer "F.Fab")
		)
		(fp_line
			(start 0.120396 0.3048)
			(end 0.120396 0.2794)
			(stroke
				(width 0.1)
				(type default)
			)
			(layer "F.Fab")
		)
		(fp_line
			(start -0.12065 0.3048)
			(end -0.67945 0.3048)
			(stroke
				(width 0.1)
				(type default)
			)
			(layer "F.Fab")
		)
		(fp_line
			(start -0.67945 0.3048)
			(end -0.67945 -0.305054)
			(stroke
				(width 0.1)
				(type default)
			)
			(layer "F.Fab")
		)
		(pad "1" smd circle
			(at -0.40005 0 90)
			(size 0 0)
			(layers "F.Cu" "F.Mask" "F.Paste")
			(net "P12V_OCP_IMON_2")
		)
		(pad "2" smd circle
			(at 0.40005 0 90)
			(size 0 0)
			(layers "F.Cu" "F.Mask" "F.Paste")
			(net "P12V_OCP_V3_2_ISENSE_MPS_TIC")
		)
	)
)
